(kicad_pcb
	(version 20241229)
	(generator "pcbnew")
	(generator_version "9.0")
	(general
		(thickness 1.61)
		(legacy_teardrops no)
	)
	(paper "A3")
	(title_block
		(title "SO-DIMM DDR5 Tester")
		(date "2025-11-26")
		(rev "1.3.0")
		(comment 9 "footprints 297-302 of 627")
	)
	(layers
		(0 "F.Cu" signal)
		(4 "In1.Cu" power)
		(6 "In2.Cu" mixed)
		(8 "In3.Cu" power)
		(10 "In4.Cu" mixed)
		(12 "In5.Cu" power)
		(14 "In6.Cu" mixed)
		(16 "In7.Cu" power)
		(18 "In8.Cu" power)
		(20 "In9.Cu" mixed)
		(22 "In10.Cu" power)
		(2 "B.Cu" signal)
		(9 "F.Adhes" user "F.Adhesive")
		(11 "B.Adhes" user "B.Adhesive")
		(13 "F.Paste" user)
		(15 "B.Paste" user)
		(5 "F.SilkS" user "F.Silkscreen")
		(7 "B.SilkS" user "B.Silkscreen")
		(1 "F.Mask" user)
		(3 "B.Mask" user)
		(17 "Dwgs.User" user "User.Drawings")
		(19 "Cmts.User" user "User.Comments")
		(21 "Eco1.User" user "User.Eco1")
		(23 "Eco2.User" user "User.Eco2")
		(25 "Edge.Cuts" user)
		(27 "Margin" user)
		(31 "F.CrtYd" user "F.Courtyard")
		(29 "B.CrtYd" user "B.Courtyard")
		(35 "F.Fab" user)
		(33 "B.Fab" user)
	)
	(footprint "antmicro-footprints:C_0603_1608Metric"
		(layer "F.Cu")
		(at 192.745501 185.523 -90)
		(descr "Capacitor SMD 0603")
		(tags "capacitor 0603")
		(property "Reference" "C182"
			(at -1.42757 -1.000252 270)
			(layer "F.SilkS")
			(hide yes)
			(effects
				(font
					(size 0.7 0.7)
					(thickness 0.15)
				)
				(justify left bottom)
			)
		)
		(property "Value" "C_22u_0603"
			(at -1.42757 1.770288 270)
			(layer "F.Fab")
			(effects
				(font
					(size 0.7 0.7)
					(thickness 0.15)
				)
				(justify left bottom)
			)
		)
		(property "Datasheet" "https://www.murata.com/products/productdetail?partno=GRM188R60J226MEA0%23"
			(at 0 0 270)
			(layer "F.Fab")
			(hide yes)
			(effects
				(font
					(size 1.27 1.27)
					(thickness 0.15)
				)
			)
		)
		(property "Author" "Antmicro"
			(at 7.222501 378.268501 0)
			(layer "F.Fab")
			(hide yes)
			(effects
				(font
					(size 1 1)
					(thickness 0.15)
				)
			)
		)
		(property "Dielectric" ""
			(at 7.222501 378.268501 0)
			(layer "F.Fab")
			(hide yes)
			(effects
				(font
					(size 1 1)
					(thickness 0.15)
				)
			)
		)
		(property "License" "Apache-2.0"
			(at 7.222501 378.268501 0)
			(layer "F.Fab")
			(hide yes)
			(effects
				(font
					(size 1 1)
					(thickness 0.15)
				)
			)
		)
		(property "MPN" "GRM188R60J226MEA0D"
			(at 7.222501 378.268501 0)
			(layer "F.Fab")
			(hide yes)
			(effects
				(font
					(size 1 1)
					(thickness 0.15)
				)
			)
		)
		(property "Manufacturer" "Murata"
			(at 7.222501 378.268501 0)
			(layer "F.Fab")
			(hide yes)
			(effects
				(font
					(size 1 1)
					(thickness 0.15)
				)
			)
		)
		(property "Val" "22u"
			(at 7.222501 378.268501 0)
			(layer "F.Fab")
			(hide yes)
			(effects
				(font
					(size 1 1)
					(thickness 0.15)
				)
			)
		)
		(property "Voltage" ""
			(at 7.222501 378.268501 0)
			(layer "F.Fab")
			(hide yes)
			(effects
				(font
					(size 1 1)
					(thickness 0.15)
				)
			)
		)
		(sheetname "/Supply/")
		(sheetfile "supply.kicad_sch")
		(attr smd)
		(fp_line
			(start -0.3 0.3)
			(end 0.3 0.3)
			(stroke
				(width 0.15)
				(type solid)
			)
			(layer "F.SilkS")
		)
		(fp_line
			(start -0.3 -0.3)
			(end 0.3 -0.3)
			(stroke
				(width 0.15)
				(type solid)
			)
			(layer "F.SilkS")
		)
		(fp_rect
			(start -1.24 -0.7)
			(end 1.24 0.7)
			(stroke
				(width 0.05)
				(type solid)
			)
			(fill no)
			(layer "F.CrtYd")
		)
		(fp_rect
			(start -0.8 -0.4)
			(end 0.8 0.4)
			(stroke
				(width 0.15)
				(type solid)
			)
			(fill no)
			(layer "F.Fab")
		)
		(pad "1" smd roundrect
			(at -0.7 0 270)
			(size 0.6 0.8)
			(layers "F.Cu" "F.Mask" "F.Paste")
			(roundrect_rratio 0.2)
			(net 1 "GND")
			(pintype "passive")
		)
		(pad "2" smd roundrect
			(at 0.7 0 270)
			(size 0.6 0.8)
			(layers "F.Cu" "F.Mask" "F.Paste")
			(roundrect_rratio 0.2)
			(net 42 "/Supply/MGTAVCC_local")
			(pintype "passive")
		)
	)
	(footprint "antmicro-footprints:C_0402_1005Metric"
		(layer "F.Cu")
		(at 78.225 160.115 -90)
		(descr "Capacitor SMD 0402")
		(tags "capacitor SMD 0402")
		(property "Reference" "C133"
			(at 0 -0.699 270)
			(layer "F.SilkS")
			(hide yes)
			(effects
				(font
					(size 0.7 0.7)
					(thickness 0.15)
				)
				(justify left bottom)
			)
		)
		(property "Value" "C_100n_0402"
			(at -1.022927 2.155213 270)
			(layer "F.Fab")
			(effects
				(font
					(size 0.7 0.7)
					(thickness 0.15)
				)
				(justify left bottom)
			)
		)
		(property "Datasheet" "https://www.murata.com/products/productdetail?partno=GRM155R61H104KE14%23"
			(at 0 0 270)
			(layer "F.Fab")
			(hide yes)
			(effects
				(font
					(size 1.27 1.27)
					(thickness 0.15)
				)
			)
		)
		(property "Author" "Antmicro"
			(at -81.89 238.34 0)
			(layer "F.Fab")
			(hide yes)
			(effects
				(font
					(size 1 1)
					(thickness 0.15)
				)
			)
		)
		(property "Dielectric" "X5R"
			(at -81.89 238.34 0)
			(layer "F.Fab")
			(hide yes)
			(effects
				(font
					(size 1 1)
					(thickness 0.15)
				)
			)
		)
		(property "License" "Apache-2.0"
			(at -81.89 238.34 0)
			(layer "F.Fab")
			(hide yes)
			(effects
				(font
					(size 1 1)
					(thickness 0.15)
				)
			)
		)
		(property "MPN" "GRM155R61H104KE14D"
			(at -81.89 238.34 0)
			(layer "F.Fab")
			(hide yes)
			(effects
				(font
					(size 1 1)
					(thickness 0.15)
				)
			)
		)
		(property "Manufacturer" "Murata"
			(at -81.89 238.34 0)
			(layer "F.Fab")
			(hide yes)
			(effects
				(font
					(size 1 1)
					(thickness 0.15)
				)
			)
		)
		(property "Val" "100n"
			(at -81.89 238.34 0)
			(layer "F.Fab")
			(hide yes)
			(effects
				(font
					(size 1 1)
					(thickness 0.15)
				)
			)
		)
		(property "Voltage" "50V"
			(at -81.89 238.34 0)
			(layer "F.Fab")
			(hide yes)
			(effects
				(font
					(size 1 1)
					(thickness 0.15)
				)
			)
		)
		(sheetname "/Debug FTDI/")
		(sheetfile "debug-ftdi.kicad_sch")
		(attr smd)
		(fp_rect
			(start -0.9659 -0.481258)
			(end 0.9649 0.458742)
			(stroke
				(width 0.05)
				(type solid)
			)
			(fill no)
			(layer "F.CrtYd")
		)
		(fp_line
			(start -0.499 0.248)
			(end -0.499 -0.25)
			(stroke
				(width 0.15)
				(type solid)
			)
			(layer "F.Fab")
		)
		(fp_line
			(start 0.499 0.248)
			(end -0.499 0.248)
			(stroke
				(width 0.15)
				(type solid)
			)
			(layer "F.Fab")
		)
		(fp_line
			(start -0.499 -0.25)
			(end 0.499 -0.25)
			(stroke
				(width 0.15)
				(type solid)
			)
			(layer "F.Fab")
		)
		(fp_line
			(start 0.499 -0.25)
			(end 0.499 0.248)
			(stroke
				(width 0.15)
				(type solid)
			)
			(layer "F.Fab")
		)
		(pad "1" smd roundrect
			(at -0.484 0 270)
			(size 0.59 0.64)
			(layers "F.Cu" "F.Mask" "F.Paste")
			(roundrect_rratio 0.25)
			(net 593 "Net-(C133-Pad1)")
			(pintype "passive")
		)
		(pad "2" smd roundrect
			(at 0.484 0 270)
			(size 0.59 0.64)
			(layers "F.Cu" "F.Mask" "F.Paste")
			(roundrect_rratio 0.25)
			(net 1 "GND")
			(pintype "passive")
		)
	)
	(footprint "antmicro-footprints:LED_0603_1608Metric_G"
		(layer "F.Cu")
		(at 92.699 197.1 -90)
		(descr "LED SMD 0603 Green")
		(tags "LED SMD 0603 Green")
		(property "Reference" "D10"
			(at -0.001 -0.901 270)
			(layer "F.SilkS")
			(hide yes)
			(effects
				(font
					(size 0.7 0.7)
					(thickness 0.15)
				)
				(justify left bottom)
			)
		)
		(property "Value" "LED_G_0603_KP-1608CGCK"
			(at -0.001 1.599 270)
			(layer "F.Fab")
			(effects
				(font
					(size 0.7 0.7)
					(thickness 0.15)
				)
				(justify left bottom)
			)
		)
		(property "Datasheet" "http://www.farnell.com/datasheets/2045956.pdf"
			(at 0 0 270)
			(layer "F.Fab")
			(hide yes)
			(effects
				(font
					(size 1.27 1.27)
					(thickness 0.15)
				)
			)
		)
		(property "Author" "Antmicro"
			(at -104.401 289.799 0)
			(layer "F.Fab")
			(hide yes)
			(effects
				(font
					(size 1 1)
					(thickness 0.15)
				)
			)
		)
		(property "License" "Apache-2.0"
			(at -104.401 289.799 0)
			(layer "F.Fab")
			(hide yes)
			(effects
				(font
					(size 1 1)
					(thickness 0.15)
				)
			)
		)
		(property "MPN" "KP-1608CGCK"
			(at -104.401 289.799 0)
			(layer "F.Fab")
			(hide yes)
			(effects
				(font
					(size 1 1)
					(thickness 0.15)
				)
			)
		)
		(property "Manufacturer" "Kingbright"
			(at -104.401 289.799 0)
			(layer "F.Fab")
			(hide yes)
			(effects
				(font
					(size 1 1)
					(thickness 0.15)
				)
			)
		)
		(sheetname "/Debug FTDI/")
		(sheetfile "debug-ftdi.kicad_sch")
		(attr smd)
		(fp_line
			(start -0.271 0.348)
			(end 0.269 0.348)
			(stroke
				(width 0.15)
				(type solid)
			)
			(layer "F.SilkS")
		)
		(fp_line
			(start 1.249 0.319)
			(end 1.249 -0.321)
			(stroke
				(width 0.15)
				(type solid)
			)
			(layer "F.SilkS")
		)
		(fp_line
			(start -0.107 -0.001)
			(end -0.291 -0.001)
			(stroke
				(width 0.1)
				(type solid)
			)
			(layer "F.SilkS")
		)
		(fp_line
			(start 0.092 -0.001)
			(end -0.107 0.198)
			(stroke
				(width 0.1)
				(type solid)
			)
			(layer "F.SilkS")
		)
		(fp_line
			(start 0.092 -0.001)
			(end 0.292 -0.001)
			(stroke
				(width 0.1)
				(type solid)
			)
			(layer "F.SilkS")
		)
		(fp_line
			(start -0.107 -0.201)
			(end -0.107 0.198)
			(stroke
				(width 0.1)
				(type solid)
			)
			(layer "F.SilkS")
		)
		(fp_line
			(start -0.107 -0.201)
			(end 0.092 -0.001)
			(stroke
				(width 0.1)
				(type solid)
			)
			(layer "F.SilkS")
		)
		(fp_line
			(start 0.092 -0.201)
			(end 0.092 0.198)
			(stroke
				(width 0.1)
				(type solid)
			)
			(layer "F.SilkS")
		)
		(fp_line
			(start -0.271 -0.349)
			(end 0.269 -0.349)
			(stroke
				(width 0.15)
				(type solid)
			)
			(layer "F.SilkS")
		)
		(fp_rect
			(start -1.2192 -0.6096)
			(end 1.27 0.6016)
			(stroke
				(width 0.05)
				(type solid)
			)
			(fill no)
			(layer "F.CrtYd")
		)
		(fp_line
			(start -0.202 0.201)
			(end 0.1 -0.001)
			(stroke
				(width 0.15)
				(type solid)
			)
			(layer "F.Fab")
		)
		(fp_line
			(start 0.198 0.201)
			(end 0.198 -0.101)
			(stroke
				(width 0.15)
				(type solid)
			)
			(layer "F.Fab")
		)
		(fp_line
			(start -0.849 0.025)
			(end -0.442 0.381)
			(stroke
				(width 0.15)
				(type solid)
			)
			(layer "F.Fab")
		)
		(fp_line
			(start -0.6 -0.001)
			(end -0.202 -0.001)
			(stroke
				(width 0.15)
				(type solid)
			)
			(layer "F.Fab")
		)
		(fp_line
			(start -0.202 -0.001)
			(end -0.202 0.201)
			(stroke
				(width 0.15)
				(type solid)
			)
			(layer "F.Fab")
		)
		(fp_line
			(start 0.1 -0.001)
			(end -0.202 -0.201)
			(stroke
				(width 0.15)
				(type solid)
			)
			(layer "F.Fab")
		)
		(fp_line
			(start 0.198 -0.001)
			(end 0.596 -0.001)
			(stroke
				(width 0.15)
				(type solid)
			)
			(layer "F.Fab")
		)
		(fp_line
			(start -0.202 -0.201)
			(end -0.202 -0.001)
			(stroke
				(width 0.15)
				(type solid)
			)
			(layer "F.Fab")
		)
		(fp_line
			(start 0.198 -0.201)
			(end 0.198 -0.101)
			(stroke
				(width 0.15)
				(type solid)
			)
			(layer "F.Fab")
		)
		(fp_rect
			(start -0.849 -0.401)
			(end 0.849 0.401)
			(stroke
				(width 0.15)
				(type solid)
			)
			(fill no)
			(layer "F.Fab")
		)
		(pad "1" smd rect
			(at -0.751 -0.001 90)
			(size 0.8 0.8)
			(layers "F.Cu" "F.Mask" "F.Paste")
			(net 315 "Net-(D10-Pad1)")
			(pinfunction "1")
			(pintype "passive")
		)
		(pad "2" smd rect
			(at 0.749 -0.001 90)
			(size 0.8 0.8)
			(layers "F.Cu" "F.Mask" "F.Paste")
			(net 1 "GND")
			(pinfunction "2")
			(pintype "passive")
		)
	)
	(footprint "antmicro-footprints:C_0402_1005Metric"
		(layer "F.Cu")
		(at 174.900501 191.076 -90)
		(descr "Capacitor SMD 0402")
		(tags "capacitor SMD 0402")
		(property "Reference" "C208"
			(at 0 -0.699 270)
			(layer "F.SilkS")
			(hide yes)
			(effects
				(font
					(size 0.7 0.7)
					(thickness 0.15)
				)
				(justify left bottom)
			)
		)
		(property "Value" "C_100n_0402"
			(at -1.022927 2.155213 270)
			(layer "F.Fab")
			(effects
				(font
					(size 0.7 0.7)
					(thickness 0.15)
				)
				(justify left bottom)
			)
		)
		(property "Datasheet" "https://www.murata.com/products/productdetail?partno=GRM155R61H104KE14%23"
			(at 0 0 270)
			(layer "F.Fab")
			(hide yes)
			(effects
				(font
					(size 1.27 1.27)
					(thickness 0.15)
				)
			)
		)
		(property "Author" "Antmicro"
			(at -16.175499 365.976501 0)
			(layer "F.Fab")
			(hide yes)
			(effects
				(font
					(size 1 1)
					(thickness 0.15)
				)
			)
		)
		(property "Dielectric" "X5R"
			(at -16.175499 365.976501 0)
			(layer "F.Fab")
			(hide yes)
			(effects
				(font
					(size 1 1)
					(thickness 0.15)
				)
			)
		)
		(property "License" "Apache-2.0"
			(at -16.175499 365.976501 0)
			(layer "F.Fab")
			(hide yes)
			(effects
				(font
					(size 1 1)
					(thickness 0.15)
				)
			)
		)
		(property "MPN" "GRM155R61H104KE14D"
			(at -16.175499 365.976501 0)
			(layer "F.Fab")
			(hide yes)
			(effects
				(font
					(size 1 1)
					(thickness 0.15)
				)
			)
		)
		(property "Manufacturer" "Murata"
			(at -16.175499 365.976501 0)
			(layer "F.Fab")
			(hide yes)
			(effects
				(font
					(size 1 1)
					(thickness 0.15)
				)
			)
		)
		(property "Val" "100n"
			(at -16.175499 365.976501 0)
			(layer "F.Fab")
			(hide yes)
			(effects
				(font
					(size 1 1)
					(thickness 0.15)
				)
			)
		)
		(property "Voltage" "50V"
			(at -16.175499 365.976501 0)
			(layer "F.Fab")
			(hide yes)
			(effects
				(font
					(size 1 1)
					(thickness 0.15)
				)
			)
		)
		(sheetname "/Supply/")
		(sheetfile "supply.kicad_sch")
		(attr smd)
		(fp_rect
			(start -0.9659 -0.481258)
			(end 0.9649 0.458742)
			(stroke
				(width 0.05)
				(type solid)
			)
			(fill no)
			(layer "F.CrtYd")
		)
		(fp_line
			(start -0.499 0.248)
			(end -0.499 -0.25)
			(stroke
				(width 0.15)
				(type solid)
			)
			(layer "F.Fab")
		)
		(fp_line
			(start 0.499 0.248)
			(end -0.499 0.248)
			(stroke
				(width 0.15)
				(type solid)
			)
			(layer "F.Fab")
		)
		(fp_line
			(start -0.499 -0.25)
			(end 0.499 -0.25)
			(stroke
				(width 0.15)
				(type solid)
			)
			(layer "F.Fab")
		)
		(fp_line
			(start 0.499 -0.25)
			(end 0.499 0.248)
			(stroke
				(width 0.15)
				(type solid)
			)
			(layer "F.Fab")
		)
		(pad "1" smd roundrect
			(at -0.484 0 270)
			(size 0.59 0.64)
			(layers "F.Cu" "F.Mask" "F.Paste")
			(roundrect_rratio 0.25)
			(net 66 "/Supply/1V0_SW")
			(pintype "passive")
		)
		(pad "2" smd roundrect
			(at 0.484 0 270)
			(size 0.59 0.64)
			(layers "F.Cu" "F.Mask" "F.Paste")
			(roundrect_rratio 0.25)
			(net 67 "/Supply/1V0_BS")
			(pintype "passive")
		)
	)
	(footprint "antmicro-footprints:R_0402_1005Metric"
		(layer "F.Cu")
		(at 196.481001 171.722 180)
		(descr "Resistor SMD 0402")
		(tags "resistor SMD 0402")
		(property "Reference" "R155"
			(at 3.731001 -0.328 180)
			(layer "F.SilkS")
			(effects
				(font
					(size 0.7 0.7)
					(thickness 0.15)
				)
				(justify left bottom)
			)
		)
		(property "Value" "R_0R_0402"
			(at -1.011843 1.772047 180)
			(layer "F.Fab")
			(effects
				(font
					(size 0.7 0.7)
					(thickness 0.15)
				)
				(justify left bottom)
			)
		)
		(property "Datasheet" "https://industrial.panasonic.com/cdbs/www-data/pdf/RDA0000/AOA0000C301.pdf"
			(at 0 0 180)
			(layer "F.Fab")
			(hide yes)
			(effects
				(font
					(size 1.27 1.27)
					(thickness 0.15)
				)
			)
		)
		(property "Author" "Antmicro"
			(at 392.962002 343.444 0)
			(layer "F.Fab")
			(hide yes)
			(effects
				(font
					(size 1 1)
					(thickness 0.15)
				)
			)
		)
		(property "Current" "1A"
			(at 392.962002 343.444 0)
			(layer "F.Fab")
			(hide yes)
			(effects
				(font
					(size 1 1)
					(thickness 0.15)
				)
			)
		)
		(property "License" "Apache-2.0"
			(at 392.962002 343.444 0)
			(layer "F.Fab")
			(hide yes)
			(effects
				(font
					(size 1 1)
					(thickness 0.15)
				)
			)
		)
		(property "MPN" "ERJ2GE0R00X"
			(at 392.962002 343.444 0)
			(layer "F.Fab")
			(hide yes)
			(effects
				(font
					(size 1 1)
					(thickness 0.15)
				)
			)
		)
		(property "Manufacturer" "Panasonic"
			(at 392.962002 343.444 0)
			(layer "F.Fab")
			(hide yes)
			(effects
				(font
					(size 1 1)
					(thickness 0.15)
				)
			)
		)
		(property "Tolerance" ""
			(at 392.962002 343.444 0)
			(layer "F.Fab")
			(hide yes)
			(effects
				(font
					(size 1 1)
					(thickness 0.15)
				)
			)
		)
		(property "Val" "0R"
			(at 392.962002 343.444 0)
			(layer "F.Fab")
			(hide yes)
			(effects
				(font
					(size 1 1)
					(thickness 0.15)
				)
			)
		)
		(sheetname "/Supply/")
		(sheetfile "supply.kicad_sch")
		(attr smd)
		(fp_rect
			(start -0.93 -0.47)
			(end 0.93 0.47)
			(stroke
				(width 0.05)
				(type solid)
			)
			(fill no)
			(layer "F.CrtYd")
		)
		(fp_rect
			(start -0.5 -0.25)
			(end 0.5 0.25)
			(stroke
				(width 0.15)
				(type solid)
			)
			(fill no)
			(layer "F.Fab")
		)
		(pad "1" smd roundrect
			(at -0.485 0 180)
			(size 0.59 0.64)
			(layers "F.Cu" "F.Mask" "F.Paste")
			(roundrect_rratio 0.25)
			(net 209 "/Supply/FB5")
			(pintype "passive")
		)
		(pad "2" smd roundrect
			(at 0.485 0 180)
			(size 0.59 0.64)
			(layers "F.Cu" "F.Mask" "F.Paste")
			(roundrect_rratio 0.25)
			(net 52 "/Supply/3V3_local")
			(pintype "passive")
		)
	)
	(footprint "antmicro-footprints:R_0402_1005Metric"
		(layer "F.Cu")
		(at 97.7 190 90)
		(descr "Resistor SMD 0402")
		(tags "resistor SMD 0402")
		(property "Reference" "R79"
			(at -1.122484 -0.772697 90)
			(layer "F.SilkS")
			(hide yes)
			(effects
				(font
					(size 0.7 0.7)
					(thickness 0.15)
				)
				(justify left bottom)
			)
		)
		(property "Value" "R_10k_0402"
			(at -1.011843 1.772047 90)
			(layer "F.Fab")
			(effects
				(font
					(size 0.7 0.7)
					(thickness 0.15)
				)
				(justify left bottom)
			)
		)
		(property "Datasheet" "https://www.bourns.com/docs/product-datasheets/cr.pdf"
			(at 0 0 90)
			(layer "F.Fab")
			(hide yes)
			(effects
				(font
					(size 1.27 1.27)
					(thickness 0.15)
				)
			)
		)
		(property "Author" "Antmicro"
			(at 287.7 92.3 0)
			(layer "F.Fab")
			(hide yes)
			(effects
				(font
					(size 1 1)
					(thickness 0.15)
				)
			)
		)
		(property "License" "Apache-2.0"
			(at 287.7 92.3 0)
			(layer "F.Fab")
			(hide yes)
			(effects
				(font
					(size 1 1)
					(thickness 0.15)
				)
			)
		)
		(property "MPN" "CR0402-FX-1002GLF"
			(at 287.7 92.3 0)
			(layer "F.Fab")
			(hide yes)
			(effects
				(font
					(size 1 1)
					(thickness 0.15)
				)
			)
		)
		(property "Manufacturer" "Bourns"
			(at 287.7 92.3 0)
			(layer "F.Fab")
			(hide yes)
			(effects
				(font
					(size 1 1)
					(thickness 0.15)
				)
			)
		)
		(property "Tolerance" "1%"
			(at 287.7 92.3 0)
			(layer "F.Fab")
			(hide yes)
			(effects
				(font
					(size 1 1)
					(thickness 0.15)
				)
			)
		)
		(property "Val" "10k"
			(at 287.7 92.3 0)
			(layer "F.Fab")
			(hide yes)
			(effects
				(font
					(size 1 1)
					(thickness 0.15)
				)
			)
		)
		(sheetname "/Debug FTDI/")
		(sheetfile "debug-ftdi.kicad_sch")
		(attr smd)
		(fp_rect
			(start -0.93 -0.47)
			(end 0.93 0.47)
			(stroke
				(width 0.05)
				(type solid)
			)
			(fill no)
			(layer "F.CrtYd")
		)
		(fp_rect
			(start -0.5 -0.25)
			(end 0.5 0.25)
			(stroke
				(width 0.15)
				(type solid)
			)
			(fill no)
			(layer "F.Fab")
		)
		(pad "1" smd roundrect
			(at -0.485 0 90)
			(size 0.59 0.64)
			(layers "F.Cu" "F.Mask" "F.Paste")
			(roundrect_rratio 0.25)
			(net 6 "/Debug FTDI/FTDI_3V3")
			(pintype "passive")
		)
		(pad "2" smd roundrect
			(at 0.485 0 90)
			(size 0.59 0.64)
			(layers "F.Cu" "F.Mask" "F.Paste")
			(roundrect_rratio 0.25)
			(net 668 "/Debug FTDI/FTDI_PWREN")
			(pintype "passive")
		)
	)
)
